(kicad_pcb
	(version 20260206)
	(generator "pcbnew")
	(generator_version "10.0")
	(general
		(thickness 1.6)
		(legacy_teardrops no)
	)
	(paper "A4")
	(title_block
		(title "01162023_DA0F0TEBIF0_F0T_Expander_BD_F_brd_V02_OCP.brd")
		(comment 1 "Grand Teton / footprints 7-12 of 9728")
	)
	(layers
		(0 "F.Cu" signal "TOP")
		(4 "In1.Cu" signal "GND")
		(6 "In2.Cu" signal "VCC")
		(8 "In3.Cu" signal "VCC1")
		(10 "In4.Cu" signal "GND1")
		(12 "In5.Cu" signal "IN1")
		(14 "In6.Cu" signal "GND2")
		(16 "In7.Cu" signal "IN2")
		(18 "In8.Cu" signal "GND3")
		(20 "In9.Cu" signal "IN3")
		(22 "In10.Cu" signal "GND4")
		(24 "In11.Cu" signal "IN4")
		(26 "In12.Cu" signal "GND5")
		(28 "In13.Cu" signal "IN5")
		(30 "In14.Cu" signal "GND6")
		(32 "In15.Cu" signal "IN6")
		(34 "In16.Cu" signal "GND7")
		(2 "B.Cu" signal "BOTTOM")
		(9 "F.Adhes" user "F.Adhesive")
		(11 "B.Adhes" user "B.Adhesive")
		(13 "F.Paste" user "Package Geometry/Pastemask Top")
		(15 "B.Paste" user "Package Geometry/Pastemask Bottom")
		(5 "F.SilkS" user "Ref Des/Silkscreen Top")
		(7 "B.SilkS" user "Ref Des/Silkscreen Bottom")
		(1 "F.Mask" user "Board Geometry/Soldermask Top")
		(3 "B.Mask" user "Board Geometry/Soldermask Bottom")
		(17 "Dwgs.User" user "User.Drawings")
		(19 "Cmts.User" user "User.Comments")
		(21 "Eco1.User" user "User.Eco1")
		(23 "Eco2.User" user "User.Eco2")
		(25 "Edge.Cuts" user "Board Geometry/Outline")
		(27 "Margin" user)
		(31 "F.CrtYd" user "Package Geometry/Place Bound Top")
		(29 "B.CrtYd" user "Package Geometry/Place Bound Bottom")
		(35 "F.Fab" user "Ref Des/Assembly Top")
		(33 "B.Fab" user "Ref Des/Assembly Bottom")
	)
	(footprint ""
		(layer "F.Cu")
		(at 250.879864 -135.62711 90)
		(property "Reference" "PD7"
			(at -3.49631 2.207006 90)
			(unlocked yes)
			(layer "F.SilkS")
			(effects
				(font
					(size 0.7874 0.5842)
					(thickness 0.1524)
				)
				(justify left)
			)
		)
		(property "Value" ""
			(at 0 0 90)
			(layer "F.Fab")
			(effects
				(font
					(size 1.27 1.27)
				)
			)
		)
		(duplicate_pad_numbers_are_jumpers no)
		(fp_line
			(start 4.107942 -1.459992)
			(end 4.107942 1.459992)
			(stroke
				(width 0.1524)
				(type default)
			)
			(layer "F.SilkS")
		)
		(fp_line
			(start -3.400044 -1.459992)
			(end 4.107942 -1.459992)
			(stroke
				(width 0.1524)
				(type default)
			)
			(layer "F.SilkS")
		)
		(fp_line
			(start 4.107942 1.459992)
			(end -3.400044 1.459992)
			(stroke
				(width 0.1524)
				(type default)
			)
			(layer "F.SilkS")
		)
		(fp_line
			(start -3.400044 1.459992)
			(end -3.400044 -1.459992)
			(stroke
				(width 0.1524)
				(type default)
			)
			(layer "F.SilkS")
		)
		(fp_poly
			(pts
				(xy 4.107942 -1.459992) (xy 4.107942 1.459992) (xy 3.308096 1.459992) (xy 3.308096 -1.459992)
			)
			(stroke
				(width 0)
				(type default)
			)
			(fill yes)
			(layer "F.SilkS")
		)
		(fp_line
			(start 2.29997 -1.459992)
			(end 2.29997 1.459992)
			(stroke
				(width 0.1)
				(type default)
			)
			(layer "F.Fab")
		)
		(fp_line
			(start -2.29997 -1.459992)
			(end 2.29997 -1.459992)
			(stroke
				(width 0.1)
				(type default)
			)
			(layer "F.Fab")
		)
		(fp_line
			(start 2.29997 1.459992)
			(end -2.29997 1.459992)
			(stroke
				(width 0.1)
				(type default)
			)
			(layer "F.Fab")
		)
		(fp_line
			(start -2.29997 1.459992)
			(end -2.29997 -1.459992)
			(stroke
				(width 0.1)
				(type default)
			)
			(layer "F.Fab")
		)
		(fp_text user "+"
			(at -4.7752 -0.12065 90)
			(unlocked yes)
			(layer "F.SilkS")
			(effects
				(font
					(size 1.905 1.4224)
					(thickness 0.1524)
				)
				(justify left)
			)
		)
		(fp_text user "-"
			(at 4.663694 2.10312 270)
			(unlocked yes)
			(layer "F.SilkS")
			(effects
				(font
					(size 1.905 1.4224)
					(thickness 0.1524)
				)
				(justify left)
			)
		)
		(fp_text user "+"
			(at -4.7752 -0.12065 90)
			(unlocked yes)
			(layer "F.Fab")
			(effects
				(font
					(size 1.905 1.4224)
					(thickness 0.1524)
				)
				(justify left)
			)
		)
		(fp_text user "-"
			(at 5.4102 0.29845 270)
			(unlocked yes)
			(layer "F.Fab")
			(effects
				(font
					(size 1.905 1.4224)
					(thickness 0.1524)
				)
				(justify left)
			)
		)
		(pad "A" smd rect
			(at -1.999996 0 180)
			(size 1.7018 2.5146)
			(layers "F.Cu" "F.Mask" "F.Paste")
			(net "GND")
		)
		(pad "C" smd rect
			(at 1.999996 0 180)
			(size 1.7018 2.5146)
			(layers "F.Cu" "F.Mask" "F.Paste")
			(net "P12V_NIC4_R")
		)
	)
	(footprint ""
		(layer "F.Cu")
		(at 406.619964 -372.877842 180)
		(property "Reference" "R6681"
			(at 0 0 180)
			(layer "F.SilkS")
			(hide yes)
			(effects
				(font
					(size 1.27 1.27)
				)
			)
		)
		(property "Value" ""
			(at 0 0 180)
			(layer "F.Fab")
			(effects
				(font
					(size 1.27 1.27)
				)
			)
		)
		(duplicate_pad_numbers_are_jumpers no)
		(fp_line
			(start 0.7874 0.4064)
			(end -0.7874 0.4064)
			(stroke
				(width 0.1524)
				(type default)
			)
			(layer "F.SilkS")
		)
		(fp_line
			(start 0.7874 -0.4064)
			(end 0.7874 0.4064)
			(stroke
				(width 0.1524)
				(type default)
			)
			(layer "F.SilkS")
		)
		(fp_line
			(start -0.7874 0.4064)
			(end -0.7874 -0.4064)
			(stroke
				(width 0.1524)
				(type default)
			)
			(layer "F.SilkS")
		)
		(fp_line
			(start -0.7874 -0.4064)
			(end 0.7874 -0.4064)
			(stroke
				(width 0.1524)
				(type default)
			)
			(layer "F.SilkS")
		)
		(fp_line
			(start 0.67945 0.3048)
			(end 0.120396 0.3048)
			(stroke
				(width 0.1)
				(type default)
			)
			(layer "F.Fab")
		)
		(fp_line
			(start 0.67945 -0.3048)
			(end 0.67945 0.3048)
			(stroke
				(width 0.1)
				(type default)
			)
			(layer "F.Fab")
		)
		(fp_line
			(start 0.12065 -0.2794)
			(end 0.12065 -0.3048)
			(stroke
				(width 0.1)
				(type default)
			)
			(layer "F.Fab")
		)
		(fp_line
			(start 0.12065 -0.3048)
			(end 0.67945 -0.3048)
			(stroke
				(width 0.1)
				(type default)
			)
			(layer "F.Fab")
		)
		(fp_line
			(start 0.120396 0.3048)
			(end 0.120396 0.2794)
			(stroke
				(width 0.1)
				(type default)
			)
			(layer "F.Fab")
		)
		(fp_line
			(start 0.120396 0.2794)
			(end -0.12065 0.2794)
			(stroke
				(width 0.1)
				(type default)
			)
			(layer "F.Fab")
		)
		(fp_line
			(start -0.12065 0.3048)
			(end -0.67945 0.3048)
			(stroke
				(width 0.1)
				(type default)
			)
			(layer "F.Fab")
		)
		(fp_line
			(start -0.12065 0.2794)
			(end -0.12065 0.3048)
			(stroke
				(width 0.1)
				(type default)
			)
			(layer "F.Fab")
		)
		(fp_line
			(start -0.12065 -0.2794)
			(end 0.12065 -0.2794)
			(stroke
				(width 0.1)
				(type default)
			)
			(layer "F.Fab")
		)
		(fp_line
			(start -0.12065 -0.305054)
			(end -0.12065 -0.2794)
			(stroke
				(width 0.1)
				(type default)
			)
			(layer "F.Fab")
		)
		(fp_line
			(start -0.67945 0.3048)
			(end -0.67945 -0.305054)
			(stroke
				(width 0.1)
				(type default)
			)
			(layer "F.Fab")
		)
		(fp_line
			(start -0.67945 -0.305054)
			(end -0.12065 -0.305054)
			(stroke
				(width 0.1)
				(type default)
			)
			(layer "F.Fab")
		)
		(pad "1" smd circle
			(at -0.40005 0 180)
			(size 0 0)
			(layers "F.Cu" "F.Mask" "F.Paste")
			(net "P3V3_AUX")
		)
		(pad "2" smd circle
			(at 0.40005 0 180)
			(size 0 0)
			(layers "F.Cu" "F.Mask" "F.Paste")
			(net "GPU_3V3IO_RSVD1")
		)
	)
	(footprint ""
		(layer "F.Cu")
		(at 396.209266 -82.642202 180)
		(property "Reference" "R1756"
			(at 0 0 180)
			(layer "F.SilkS")
			(hide yes)
			(effects
				(font
					(size 1.27 1.27)
				)
			)
		)
		(property "Value" ""
			(at 0 0 180)
			(layer "F.Fab")
			(effects
				(font
					(size 1.27 1.27)
				)
			)
		)
		(duplicate_pad_numbers_are_jumpers no)
		(fp_line
			(start 0.7874 0.4064)
			(end -0.7874 0.4064)
			(stroke
				(width 0.1524)
				(type default)
			)
			(layer "F.SilkS")
		)
		(fp_line
			(start 0.7874 -0.4064)
			(end 0.7874 0.4064)
			(stroke
				(width 0.1524)
				(type default)
			)
			(layer "F.SilkS")
		)
		(fp_line
			(start -0.7874 0.4064)
			(end -0.7874 -0.4064)
			(stroke
				(width 0.1524)
				(type default)
			)
			(layer "F.SilkS")
		)
		(fp_line
			(start -0.7874 -0.4064)
			(end 0.7874 -0.4064)
			(stroke
				(width 0.1524)
				(type default)
			)
			(layer "F.SilkS")
		)
		(fp_line
			(start 0.67945 0.3048)
			(end 0.120396 0.3048)
			(stroke
				(width 0.1)
				(type default)
			)
			(layer "F.Fab")
		)
		(fp_line
			(start 0.67945 -0.3048)
			(end 0.67945 0.3048)
			(stroke
				(width 0.1)
				(type default)
			)
			(layer "F.Fab")
		)
		(fp_line
			(start 0.12065 -0.2794)
			(end 0.12065 -0.3048)
			(stroke
				(width 0.1)
				(type default)
			)
			(layer "F.Fab")
		)
		(fp_line
			(start 0.12065 -0.3048)
			(end 0.67945 -0.3048)
			(stroke
				(width 0.1)
				(type default)
			)
			(layer "F.Fab")
		)
		(fp_line
			(start 0.120396 0.3048)
			(end 0.120396 0.2794)
			(stroke
				(width 0.1)
				(type default)
			)
			(layer "F.Fab")
		)
		(fp_line
			(start 0.120396 0.2794)
			(end -0.12065 0.2794)
			(stroke
				(width 0.1)
				(type default)
			)
			(layer "F.Fab")
		)
		(fp_line
			(start -0.12065 0.3048)
			(end -0.67945 0.3048)
			(stroke
				(width 0.1)
				(type default)
			)
			(layer "F.Fab")
		)
		(fp_line
			(start -0.12065 0.2794)
			(end -0.12065 0.3048)
			(stroke
				(width 0.1)
				(type default)
			)
			(layer "F.Fab")
		)
		(fp_line
			(start -0.12065 -0.2794)
			(end 0.12065 -0.2794)
			(stroke
				(width 0.1)
				(type default)
			)
			(layer "F.Fab")
		)
		(fp_line
			(start -0.12065 -0.305054)
			(end -0.12065 -0.2794)
			(stroke
				(width 0.1)
				(type default)
			)
			(layer "F.Fab")
		)
		(fp_line
			(start -0.67945 0.3048)
			(end -0.67945 -0.305054)
			(stroke
				(width 0.1)
				(type default)
			)
			(layer "F.Fab")
		)
		(fp_line
			(start -0.67945 -0.305054)
			(end -0.12065 -0.305054)
			(stroke
				(width 0.1)
				(type default)
			)
			(layer "F.Fab")
		)
		(pad "1" smd circle
			(at -0.40005 0 180)
			(size 0 0)
			(layers "F.Cu" "F.Mask" "F.Paste")
			(net "P3V3_AUX")
		)
		(pad "2" smd circle
			(at 0.40005 0 180)
			(size 0 0)
			(layers "F.Cu" "F.Mask" "F.Paste")
			(net "SMB_BIC_I2C6_MUX_CLK_R_SDA")
		)
	)
	(footprint ""
		(layer "F.Cu")
		(at 102.790244 -10.534142 -90)
		(property "Reference" "R1654"
			(at 0 0 270)
			(layer "F.SilkS")
			(hide yes)
			(effects
				(font
					(size 1.27 1.27)
				)
			)
		)
		(property "Value" ""
			(at 0 0 270)
			(layer "F.Fab")
			(effects
				(font
					(size 1.27 1.27)
				)
			)
		)
		(duplicate_pad_numbers_are_jumpers no)
		(fp_line
			(start -0.7874 0.4064)
			(end -0.7874 -0.4064)
			(stroke
				(width 0.1524)
				(type default)
			)
			(layer "F.SilkS")
		)
		(fp_line
			(start 0.7874 0.4064)
			(end -0.7874 0.4064)
			(stroke
				(width 0.1524)
				(type default)
			)
			(layer "F.SilkS")
		)
		(fp_line
			(start -0.7874 -0.4064)
			(end 0.7874 -0.4064)
			(stroke
				(width 0.1524)
				(type default)
			)
			(layer "F.SilkS")
		)
		(fp_line
			(start 0.7874 -0.4064)
			(end 0.7874 0.4064)
			(stroke
				(width 0.1524)
				(type default)
			)
			(layer "F.SilkS")
		)
		(fp_line
			(start -0.67945 0.3048)
			(end -0.67945 -0.305054)
			(stroke
				(width 0.1)
				(type default)
			)
			(layer "F.Fab")
		)
		(fp_line
			(start -0.12065 0.3048)
			(end -0.67945 0.3048)
			(stroke
				(width 0.1)
				(type default)
			)
			(layer "F.Fab")
		)
		(fp_line
			(start 0.120396 0.3048)
			(end 0.120396 0.2794)
			(stroke
				(width 0.1)
				(type default)
			)
			(layer "F.Fab")
		)
		(fp_line
			(start 0.67945 0.3048)
			(end 0.120396 0.3048)
			(stroke
				(width 0.1)
				(type default)
			)
			(layer "F.Fab")
		)
		(fp_line
			(start -0.12065 0.2794)
			(end -0.12065 0.3048)
			(stroke
				(width 0.1)
				(type default)
			)
			(layer "F.Fab")
		)
		(fp_line
			(start 0.120396 0.2794)
			(end -0.12065 0.2794)
			(stroke
				(width 0.1)
				(type default)
			)
			(layer "F.Fab")
		)
		(fp_line
			(start -0.12065 -0.2794)
			(end 0.12065 -0.2794)
			(stroke
				(width 0.1)
				(type default)
			)
			(layer "F.Fab")
		)
		(fp_line
			(start 0.12065 -0.2794)
			(end 0.12065 -0.3048)
			(stroke
				(width 0.1)
				(type default)
			)
			(layer "F.Fab")
		)
		(fp_line
			(start 0.12065 -0.3048)
			(end 0.67945 -0.3048)
			(stroke
				(width 0.1)
				(type default)
			)
			(layer "F.Fab")
		)
		(fp_line
			(start 0.67945 -0.3048)
			(end 0.67945 0.3048)
			(stroke
				(width 0.1)
				(type default)
			)
			(layer "F.Fab")
		)
		(fp_line
			(start -0.67945 -0.305054)
			(end -0.12065 -0.305054)
			(stroke
				(width 0.1)
				(type default)
			)
			(layer "F.Fab")
		)
		(fp_line
			(start -0.12065 -0.305054)
			(end -0.12065 -0.2794)
			(stroke
				(width 0.1)
				(type default)
			)
			(layer "F.Fab")
		)
		(pad "1" smd circle
			(at -0.40005 0 270)
			(size 0 0)
			(layers "F.Cu" "F.Mask" "F.Paste")
			(net "SMB_ISO_SSD3_R_SDA")
		)
		(pad "2" smd circle
			(at 0.40005 0 270)
			(size 0 0)
			(layers "F.Cu" "F.Mask" "F.Paste")
			(net "SMB_ISO_SSD3_SDA")
		)
	)
	(footprint ""
		(layer "F.Cu")
		(at 284.467808 -53.051456)
		(property "Reference" "R4468"
			(at 0 0 0)
			(layer "F.SilkS")
			(hide yes)
			(effects
				(font
					(size 1.27 1.27)
				)
			)
		)
		(property "Value" ""
			(at 0 0 0)
			(layer "F.Fab")
			(effects
				(font
					(size 1.27 1.27)
				)
			)
		)
		(duplicate_pad_numbers_are_jumpers no)
		(fp_line
			(start -0.7874 -0.4064)
			(end 0.7874 -0.4064)
			(stroke
				(width 0.1524)
				(type default)
			)
			(layer "F.SilkS")
		)
		(fp_line
			(start -0.7874 0.4064)
			(end -0.7874 -0.4064)
			(stroke
				(width 0.1524)
				(type default)
			)
			(layer "F.SilkS")
		)
		(fp_line
			(start 0.7874 -0.4064)
			(end 0.7874 0.4064)
			(stroke
				(width 0.1524)
				(type default)
			)
			(layer "F.SilkS")
		)
		(fp_line
			(start 0.7874 0.4064)
			(end -0.7874 0.4064)
			(stroke
				(width 0.1524)
				(type default)
			)
			(layer "F.SilkS")
		)
		(fp_line
			(start -0.67945 -0.305054)
			(end -0.12065 -0.305054)
			(stroke
				(width 0.1)
				(type default)
			)
			(layer "F.Fab")
		)
		(fp_line
			(start -0.67945 0.3048)
			(end -0.67945 -0.305054)
			(stroke
				(width 0.1)
				(type default)
			)
			(layer "F.Fab")
		)
		(fp_line
			(start -0.12065 -0.305054)
			(end -0.12065 -0.2794)
			(stroke
				(width 0.1)
				(type default)
			)
			(layer "F.Fab")
		)
		(fp_line
			(start -0.12065 -0.2794)
			(end 0.12065 -0.2794)
			(stroke
				(width 0.1)
				(type default)
			)
			(layer "F.Fab")
		)
		(fp_line
			(start -0.12065 0.2794)
			(end -0.12065 0.3048)
			(stroke
				(width 0.1)
				(type default)
			)
			(layer "F.Fab")
		)
		(fp_line
			(start -0.12065 0.3048)
			(end -0.67945 0.3048)
			(stroke
				(width 0.1)
				(type default)
			)
			(layer "F.Fab")
		)
		(fp_line
			(start 0.120396 0.2794)
			(end -0.12065 0.2794)
			(stroke
				(width 0.1)
				(type default)
			)
			(layer "F.Fab")
		)
		(fp_line
			(start 0.120396 0.3048)
			(end 0.120396 0.2794)
			(stroke
				(width 0.1)
				(type default)
			)
			(layer "F.Fab")
		)
		(fp_line
			(start 0.12065 -0.3048)
			(end 0.67945 -0.3048)
			(stroke
				(width 0.1)
				(type default)
			)
			(layer "F.Fab")
		)
		(fp_line
			(start 0.12065 -0.2794)
			(end 0.12065 -0.3048)
			(stroke
				(width 0.1)
				(type default)
			)
			(layer "F.Fab")
		)
		(fp_line
			(start 0.67945 -0.3048)
			(end 0.67945 0.3048)
			(stroke
				(width 0.1)
				(type default)
			)
			(layer "F.Fab")
		)
		(fp_line
			(start 0.67945 0.3048)
			(end 0.120396 0.3048)
			(stroke
				(width 0.1)
				(type default)
			)
			(layer "F.Fab")
		)
		(pad "1" smd circle
			(at -0.40005 0)
			(size 0 0)
			(layers "F.Cu" "F.Mask" "F.Paste")
			(net "PWRGD_P12V_SSD9")
		)
		(pad "2" smd circle
			(at 0.40005 0)
			(size 0 0)
			(layers "F.Cu" "F.Mask" "F.Paste")
			(net "PWRGD_P12V_SSD9_R")
		)
	)
	(footprint ""
		(layer "F.Cu")
		(at 188.27496 -48.753014 180)
		(property "Reference" "C318"
			(at 0 0 180)
			(layer "F.SilkS")
			(hide yes)
			(effects
				(font
					(size 1.27 1.27)
				)
			)
		)
		(property "Value" ""
			(at 0 0 180)
			(layer "F.Fab")
			(effects
				(font
					(size 1.27 1.27)
				)
			)
		)
		(duplicate_pad_numbers_are_jumpers no)
		(fp_line
			(start 0.7874 0.4064)
			(end -0.7874 0.4064)
			(stroke
				(width 0.1524)
				(type default)
			)
			(layer "F.SilkS")
		)
		(fp_line
			(start 0.7874 -0.4064)
			(end 0.7874 0.4064)
			(stroke
				(width 0.1524)
				(type default)
			)
			(layer "F.SilkS")
		)
		(fp_line
			(start -0.7874 0.4064)
			(end -0.7874 -0.4064)
			(stroke
				(width 0.1524)
				(type default)
			)
			(layer "F.SilkS")
		)
		(fp_line
			(start -0.7874 -0.4064)
			(end 0.7874 -0.4064)
			(stroke
				(width 0.1524)
				(type default)
			)
			(layer "F.SilkS")
		)
		(fp_line
			(start 0.67945 0.3048)
			(end 0.120396 0.3048)
			(stroke
				(width 0.1)
				(type default)
			)
			(layer "F.Fab")
		)
		(fp_line
			(start 0.67945 -0.3048)
			(end 0.67945 0.3048)
			(stroke
				(width 0.1)
				(type default)
			)
			(layer "F.Fab")
		)
		(fp_line
			(start 0.12065 -0.2794)
			(end 0.12065 -0.3048)
			(stroke
				(width 0.1)
				(type default)
			)
			(layer "F.Fab")
		)
		(fp_line
			(start 0.12065 -0.3048)
			(end 0.67945 -0.3048)
			(stroke
				(width 0.1)
				(type default)
			)
			(layer "F.Fab")
		)
		(fp_line
			(start 0.120396 0.3048)
			(end 0.120396 0.2794)
			(stroke
				(width 0.1)
				(type default)
			)
			(layer "F.Fab")
		)
		(fp_line
			(start 0.120396 0.2794)
			(end -0.12065 0.2794)
			(stroke
				(width 0.1)
				(type default)
			)
			(layer "F.Fab")
		)
		(fp_line
			(start -0.12065 0.3048)
			(end -0.67945 0.3048)
			(stroke
				(width 0.1)
				(type default)
			)
			(layer "F.Fab")
		)
		(fp_line
			(start -0.12065 0.2794)
			(end -0.12065 0.3048)
			(stroke
				(width 0.1)
				(type default)
			)
			(layer "F.Fab")
		)
		(fp_line
			(start -0.12065 -0.2794)
			(end 0.12065 -0.2794)
			(stroke
				(width 0.1)
				(type default)
			)
			(layer "F.Fab")
		)
		(fp_line
			(start -0.12065 -0.305054)
			(end -0.12065 -0.2794)
			(stroke
				(width 0.1)
				(type default)
			)
			(layer "F.Fab")
		)
		(fp_line
			(start -0.67945 0.3048)
			(end -0.67945 -0.305054)
			(stroke
				(width 0.1)
				(type default)
			)
			(layer "F.Fab")
		)
		(fp_line
			(start -0.67945 -0.305054)
			(end -0.12065 -0.305054)
			(stroke
				(width 0.1)
				(type default)
			)
			(layer "F.Fab")
		)
		(pad "1" smd circle
			(at -0.40005 0 180)
			(size 0 0)
			(layers "F.Cu" "F.Mask" "F.Paste")
			(net "P3V3_AUX")
		)
		(pad "2" smd circle
			(at 0.40005 0 180)
			(size 0 0)
			(layers "F.Cu" "F.Mask" "F.Paste")
			(net "GND")
		)
	)
)
